# BASEBOARD_FAB2 (Tioga Pass) — schematic netlist excerpt (pin names and nets, part order shuffled) for the footprints in the layout excerpt that follows; sources: Cadence DE-HDL packaged netlist, KiCad conversion of Wiwynn_Tioga_Pass_MB.brd

C5G20  CAP  100UF 4V 20% X5R  pkg 0805  page 217 : A = PVDDQ_ABC ; B = GND
R4G21  RES  1.00K 1% CHIP  pkg 0402  page 98 : A = PVDDQ_ABC ; B = M_C_VREF
C4C11  CAP_A  22.0UF 4V 20% X6S  pkg 0603V  page 205 : A = PVSA_CPU0 ; B = GND

(kicad_pcb
	(version 20260206)
	(generator "pcbnew")
	(generator_version "10.0")
	(general
		(thickness 1.6)
		(legacy_teardrops no)
	)
	(paper "A4")
	(title_block
		(title "Wiwynn_Tioga_Pass_MB.brd")
		(comment 1 "Tioga Pass / footprints 1869-1871 of 4770")
	)
	(layers
		(0 "F.Cu" signal "TOP")
		(4 "In1.Cu" signal "L2GND")
		(6 "In2.Cu" signal "L3")
		(8 "In3.Cu" signal "L4GND")
		(10 "In4.Cu" signal "L5")
		(12 "In5.Cu" signal "L6GND")
		(14 "In6.Cu" signal "L7VCC")
		(16 "In7.Cu" signal "L8VCC")
		(18 "In8.Cu" signal "L9GND")
		(20 "In9.Cu" signal "L10")
		(22 "In10.Cu" signal "L11GND")
		(24 "In11.Cu" signal "L12")
		(26 "In12.Cu" signal "L13GND")
		(2 "B.Cu" signal "BOTTOM")
		(9 "F.Adhes" user "F.Adhesive")
		(11 "B.Adhes" user "B.Adhesive")
		(13 "F.Paste" user "Package Geometry/Pastemask Top")
		(15 "B.Paste" user "Package Geometry/Pastemask Bottom")
		(5 "F.SilkS" user "Ref Des/Silkscreen Top")
		(7 "B.SilkS" user "Ref Des/Silkscreen Bottom")
		(1 "F.Mask" user "Board Geometry/Soldermask Top")
		(3 "B.Mask" user "Board Geometry/Soldermask Bottom")
		(17 "Dwgs.User" user "User.Drawings")
		(19 "Cmts.User" user "User.Comments")
		(21 "Eco1.User" user "User.Eco1")
		(23 "Eco2.User" user "User.Eco2")
		(25 "Edge.Cuts" user "Board Geometry/Outline")
		(27 "Margin" user)
		(31 "F.CrtYd" user "Package Geometry/Place Bound Top")
		(29 "B.CrtYd" user "Package Geometry/Place Bound Bottom")
		(35 "F.Fab" user "Ref Des/Assembly Top")
		(33 "B.Fab" user "Ref Des/Assembly Bottom")
	)
	(footprint ""
		(layer "F.Cu")
		(at 259.4356 -3.321812 90)
		(property "Reference" "C5G20"
			(at 0 0 90)
			(layer "F.SilkS")
			(hide yes)
			(effects
				(font
					(size 1.27 1.27)
				)
			)
		)
		(property "Value" ""
			(at 0 0 90)
			(layer "F.Fab")
			(effects
				(font
					(size 1.27 1.27)
				)
			)
		)
		(duplicate_pad_numbers_are_jumpers no)
		(fp_rect
			(start -0.7239 -0.2159)
			(end 0.7239 1.9939)
			(stroke
				(width 0)
				(type default)
			)
			(fill no)
			(layer "F.CrtYd")
		)
		(fp_line
			(start 0.7239 -0.2159)
			(end -0.7239 -0.2159)
			(stroke
				(width 0.1)
				(type default)
			)
			(layer "F.Fab")
		)
		(fp_line
			(start -0.7239 -0.2159)
			(end -0.7239 1.9939)
			(stroke
				(width 0.1)
				(type default)
			)
			(layer "F.Fab")
		)
		(fp_line
			(start 0.7239 1.9939)
			(end 0.7239 -0.2159)
			(stroke
				(width 0.1)
				(type default)
			)
			(layer "F.Fab")
		)
		(fp_line
			(start -0.7239 1.9939)
			(end 0.7239 1.9939)
			(stroke
				(width 0.1)
				(type default)
			)
			(layer "F.Fab")
		)
		(pad "1" smd rect
			(at 0 0 90)
			(size 1.27 1.016)
			(layers "F.Cu" "F.Mask" "F.Paste")
			(net "PVDDQ_ABC")
		)
		(pad "2" smd rect
			(at 0 1.778 90)
			(size 1.27 1.016)
			(layers "F.Cu" "F.Mask" "F.Paste")
			(net "GND")
		)
		(zone
			(layer "F.Cu")
			(hatch none 0.5)
			(connect_pads
				(clearance 0)
			)
			(min_thickness 0.25)
			(keepout
				(tracks not_allowed)
				(vias allowed)
				(pads allowed)
				(copperpour not_allowed)
				(footprints allowed)
			)
			(placement
				(enabled no)
				(sheetname "")
			)
			(fill
				(thermal_gap 0.5)
				(thermal_bridge_width 0.5)
				(island_removal_mode 0)
			)
			(polygon
				(pts
					(xy 259.9436 -2.686812) (xy 260.7056 -2.686812) (xy 260.7056 -3.956812) (xy 259.9436 -3.956812)
				)
			)
		)
	)
	(footprint ""
		(layer "F.Cu")
		(at 193.675 -3.7465)
		(property "Reference" "R4G21"
			(at 0 0 0)
			(layer "F.SilkS")
			(hide yes)
			(effects
				(font
					(size 1.27 1.27)
				)
			)
		)
		(property "Value" ""
			(at 0 0 0)
			(layer "F.Fab")
			(effects
				(font
					(size 1.27 1.27)
				)
			)
		)
		(duplicate_pad_numbers_are_jumpers no)
		(fp_poly
			(pts
				(xy -0.2794 -0.1016) (xy 0.2794 -0.1016) (xy 0.2794 0.9906) (xy -0.2794 0.9906)
			)
			(stroke
				(width 0)
				(type default)
			)
			(fill no)
			(layer "F.CrtYd")
		)
		(fp_line
			(start -0.2794 -0.1016)
			(end -0.2794 0.9906)
			(stroke
				(width 0.1)
				(type default)
			)
			(layer "F.Fab")
		)
		(fp_line
			(start -0.2794 0.9906)
			(end 0.2794 0.9906)
			(stroke
				(width 0.1)
				(type default)
			)
			(layer "F.Fab")
		)
		(fp_line
			(start 0.2794 -0.1016)
			(end -0.2794 -0.1016)
			(stroke
				(width 0.1)
				(type default)
			)
			(layer "F.Fab")
		)
		(fp_line
			(start 0.2794 0.9906)
			(end 0.2794 -0.1016)
			(stroke
				(width 0.1)
				(type default)
			)
			(layer "F.Fab")
		)
		(pad "1" smd rect
			(at 0 0)
			(size 0.508 0.508)
			(layers "F.Cu" "F.Mask" "F.Paste")
			(net "PVDDQ_ABC")
		)
		(pad "2" smd rect
			(at 0 0.889)
			(size 0.508 0.508)
			(layers "F.Cu" "F.Mask" "F.Paste")
			(net "M_C_VREF")
		)
		(zone
			(layer "F.Cu")
			(hatch none 0.5)
			(connect_pads
				(clearance 0)
			)
			(min_thickness 0.25)
			(keepout
				(tracks allowed)
				(vias not_allowed)
				(pads allowed)
				(copperpour not_allowed)
				(footprints allowed)
			)
			(placement
				(enabled no)
				(sheetname "")
			)
			(fill
				(thermal_gap 0.5)
				(thermal_bridge_width 0.5)
				(island_removal_mode 0)
			)
			(polygon
				(pts
					(xy 193.421 -3.4925) (xy 193.929 -3.4925) (xy 193.929 -3.1115) (xy 193.421 -3.1115)
				)
			)
		)
		(zone
			(layer "F.Cu")
			(hatch none 0.5)
			(connect_pads
				(clearance 0)
			)
			(min_thickness 0.25)
			(keepout
				(tracks not_allowed)
				(vias allowed)
				(pads allowed)
				(copperpour not_allowed)
				(footprints allowed)
			)
			(placement
				(enabled no)
				(sheetname "")
			)
			(fill
				(thermal_gap 0.5)
				(thermal_bridge_width 0.5)
				(island_removal_mode 0)
			)
			(polygon
				(pts
					(xy 193.421 -3.1115) (xy 193.929 -3.1115) (xy 193.929 -3.4925) (xy 193.421 -3.4925)
				)
			)
		)
	)
	(footprint ""
		(layer "F.Cu")
		(at 214.8586 -94.4372)
		(property "Reference" "C4C11"
			(at 0.97536 0.76708 270)
			(unlocked yes)
			(layer "F.SilkS")
			(effects
				(font
					(size 0.4064 0.254)
					(thickness 0.1524)
				)
			)
		)
		(property "Value" ""
			(at 0 0 0)
			(layer "F.Fab")
			(effects
				(font
					(size 1.27 1.27)
				)
			)
		)
		(duplicate_pad_numbers_are_jumpers no)
		(fp_poly
			(pts
				(xy -0.4953 -0.2032) (xy 0.4953 -0.2032) (xy 0.4953 1.6002) (xy -0.4953 1.6002)
			)
			(stroke
				(width 0)
				(type default)
			)
			(fill no)
			(layer "F.CrtYd")
		)
		(fp_line
			(start -0.4953 -0.2032)
			(end 0.4953 -0.2032)
			(stroke
				(width 0.1)
				(type default)
			)
			(layer "F.Fab")
		)
		(fp_line
			(start -0.4953 1.6002)
			(end -0.4953 -0.2032)
			(stroke
				(width 0.1)
				(type default)
			)
			(layer "F.Fab")
		)
		(fp_line
			(start 0.4953 -0.2032)
			(end 0.4953 1.6002)
			(stroke
				(width 0.1)
				(type default)
			)
			(layer "F.Fab")
		)
		(fp_line
			(start 0.4953 1.6002)
			(end -0.4953 1.6002)
			(stroke
				(width 0.1)
				(type default)
			)
			(layer "F.Fab")
		)
		(pad "1" smd rect
			(at 0 0)
			(size 0.762 0.889)
			(layers "F.Cu" "F.Mask" "F.Paste")
			(net "PVSA_CPU0")
		)
		(pad "2" smd rect
			(at 0 1.397)
			(size 0.762 0.889)
			(layers "F.Cu" "F.Mask" "F.Paste")
			(net "GND")
		)
		(zone
			(layer "F.Cu")
			(hatch none 0.5)
			(connect_pads
				(clearance 0)
			)
			(min_thickness 0.25)
			(keepout
				(tracks not_allowed)
				(vias allowed)
				(pads allowed)
				(copperpour not_allowed)
				(footprints allowed)
			)
			(placement
				(enabled no)
				(sheetname "")
			)
			(fill
				(thermal_gap 0.5)
				(thermal_bridge_width 0.5)
				(island_removal_mode 0)
			)
			(polygon
				(pts
					(xy 214.4776 -93.9927) (xy 215.2396 -93.9927) (xy 215.2396 -93.4847) (xy 214.4776 -93.4847)
				)
			)
		)
	)
)
